#ISCELL
  mstr_misc dns *
  *
#ISCELL
  mstr_symbols cad_note *
  *
#ISCELL
  mstr_symbols design_note *
  *
#ISCELL
  mstr_symbols intel_corp_bpage *
  *
#CELL
  mstr_ttl ttl1g126_a *
  page142_i1
#ISCELL
  mstr_standard offpage *
  page142_i11
#ISCELL
  mstr_standard offpage *
  page142_i12
#ISCELL
  mstr_standard offpage *
  page142_i13
#ISCELL
  mstr_standard offpage *
  page142_i17
#CELL
  mstr_discrete res *
  page142_i18
#ISCELL
  mstr_standard offpage *
  page142_i19
#CELL
  mstr_discrete res *
  page142_i2
#CELL
  dev_discrete cap_a *
  page142_i20
#ISCELL
  mstr_symbols p3v3_stby *
  page142_i21
#ISCELL
  mstr_symbols gnd *
  page142_i22
#CELL
  mstr_discrete res *
  page142_i23
#ISCELL
  mstr_symbols p3v3_stby *
  page142_i24
#CELL
  mstr_discrete res *
  page142_i28
#CELL
  mstr_discrete res *
  page142_i3
#CELL
  mstr_discrete res *
  page142_i30
#CELL
  mstr_discrete res *
  page142_i31
#CELL
  mstr_discrete res *
  page142_i32
#CELL
  mstr_discrete res *
  page142_i33
#ISCELL
  mstr_symbols p3v3_stby *
  page142_i4
#ISCELL
  mstr_standard offpage *
  page142_i5
